(kicad_pcb
	(version 20260206)
	(generator "pcbnew")
	(generator_version "10.0")
	(general
		(thickness 1.6)
		(legacy_teardrops no)
	)
	(paper "A4")
	(title_block
		(title "04192023_DAF0TMB3IC0_F0TG_MB_C_brd_V02_OCP.brd")
		(comment 1 "Grand Teton / footprints 6474-6481 of 8354")
	)
	(layers
		(0 "F.Cu" signal "TOP")
		(4 "In1.Cu" signal "GND")
		(6 "In2.Cu" signal "IN1")
		(8 "In3.Cu" signal "GND1")
		(10 "In4.Cu" signal "IN2")
		(12 "In5.Cu" signal "GND2")
		(14 "In6.Cu" signal "IN3")
		(16 "In7.Cu" signal "GND3")
		(18 "In8.Cu" signal "VCC")
		(20 "In9.Cu" signal "VCC1")
		(22 "In10.Cu" signal "GND4")
		(24 "In11.Cu" signal "IN4")
		(26 "In12.Cu" signal "GND5")
		(28 "In13.Cu" signal "IN5")
		(30 "In14.Cu" signal "GND6")
		(32 "In15.Cu" signal "IN6")
		(34 "In16.Cu" signal "GND7")
		(2 "B.Cu" signal "BOTTOM")
		(9 "F.Adhes" user "F.Adhesive")
		(11 "B.Adhes" user "B.Adhesive")
		(13 "F.Paste" user "Package Geometry/Pastemask Top")
		(15 "B.Paste" user "Package Geometry/Pastemask Bottom")
		(5 "F.SilkS" user "Ref Des/Silkscreen Top")
		(7 "B.SilkS" user "Ref Des/Silkscreen Bottom")
		(1 "F.Mask" user "Board Geometry/Soldermask Top")
		(3 "B.Mask" user "Board Geometry/Soldermask Bottom")
		(17 "Dwgs.User" user "User.Drawings")
		(19 "Cmts.User" user "User.Comments")
		(21 "Eco1.User" user "User.Eco1")
		(23 "Eco2.User" user "User.Eco2")
		(25 "Edge.Cuts" user "Board Geometry/Outline")
		(27 "Margin" user)
		(31 "F.CrtYd" user "Package Geometry/Place Bound Top")
		(29 "B.CrtYd" user "Package Geometry/Place Bound Bottom")
		(35 "F.Fab" user "Ref Des/Assembly Top")
		(33 "B.Fab" user "Ref Des/Assembly Bottom")
	)
	(footprint ""
		(layer "B.Cu")
		(at 230.505 -243.2431 -90)
		(property "Reference" "R326"
			(at 0 0 90)
			(layer "B.SilkS")
			(hide yes)
			(effects
				(font
					(size 1.27 1.27)
				)
				(justify mirror)
			)
		)
		(property "Value" ""
			(at 0 0 90)
			(layer "B.Fab")
			(effects
				(font
					(size 1.27 1.27)
				)
				(justify mirror)
			)
		)
		(duplicate_pad_numbers_are_jumpers no)
		(fp_line
			(start -0.7874 0.4064)
			(end 0.7874 0.4064)
			(stroke
				(width 0.1524)
				(type default)
			)
			(layer "B.SilkS")
		)
		(fp_line
			(start 0.7874 0.4064)
			(end 0.7874 -0.4064)
			(stroke
				(width 0.1524)
				(type default)
			)
			(layer "B.SilkS")
		)
		(fp_line
			(start -0.7874 -0.4064)
			(end -0.7874 0.4064)
			(stroke
				(width 0.1524)
				(type default)
			)
			(layer "B.SilkS")
		)
		(fp_line
			(start 0.7874 -0.4064)
			(end -0.7874 -0.4064)
			(stroke
				(width 0.1524)
				(type default)
			)
			(layer "B.SilkS")
		)
		(fp_line
			(start -0.67945 0.3048)
			(end -0.120396 0.3048)
			(stroke
				(width 0.1)
				(type default)
			)
			(layer "B.Fab")
		)
		(fp_line
			(start -0.120396 0.3048)
			(end -0.120396 0.2794)
			(stroke
				(width 0.1)
				(type default)
			)
			(layer "B.Fab")
		)
		(fp_line
			(start 0.12065 0.3048)
			(end 0.67945 0.3048)
			(stroke
				(width 0.1)
				(type default)
			)
			(layer "B.Fab")
		)
		(fp_line
			(start 0.67945 0.3048)
			(end 0.67945 -0.305054)
			(stroke
				(width 0.1)
				(type default)
			)
			(layer "B.Fab")
		)
		(fp_line
			(start -0.120396 0.2794)
			(end 0.12065 0.2794)
			(stroke
				(width 0.1)
				(type default)
			)
			(layer "B.Fab")
		)
		(fp_line
			(start 0.12065 0.2794)
			(end 0.12065 0.3048)
			(stroke
				(width 0.1)
				(type default)
			)
			(layer "B.Fab")
		)
		(fp_line
			(start -0.12065 -0.2794)
			(end -0.12065 -0.3048)
			(stroke
				(width 0.1)
				(type default)
			)
			(layer "B.Fab")
		)
		(fp_line
			(start 0.12065 -0.2794)
			(end -0.12065 -0.2794)
			(stroke
				(width 0.1)
				(type default)
			)
			(layer "B.Fab")
		)
		(fp_line
			(start -0.67945 -0.3048)
			(end -0.67945 0.3048)
			(stroke
				(width 0.1)
				(type default)
			)
			(layer "B.Fab")
		)
		(fp_line
			(start -0.12065 -0.3048)
			(end -0.67945 -0.3048)
			(stroke
				(width 0.1)
				(type default)
			)
			(layer "B.Fab")
		)
		(fp_line
			(start 0.12065 -0.305054)
			(end 0.12065 -0.2794)
			(stroke
				(width 0.1)
				(type default)
			)
			(layer "B.Fab")
		)
		(fp_line
			(start 0.67945 -0.305054)
			(end 0.12065 -0.305054)
			(stroke
				(width 0.1)
				(type default)
			)
			(layer "B.Fab")
		)
		(pad "1" smd rect
			(at 0.40005 0 270)
			(size 0.4572 0.508)
			(layers "B.Cu" "B.Mask" "B.Paste")
			(net "SMB_CPU0_CPU1_APML_SDA_R2")
		)
		(pad "2" smd rect
			(at -0.40005 0 270)
			(size 0.4572 0.508)
			(layers "B.Cu" "B.Mask" "B.Paste")
			(net "SMB_CPU0_CPU1_APML_MUX2_SDA")
		)
	)
	(footprint ""
		(layer "B.Cu")
		(at 115.705636 -36.138866 90)
		(property "Reference" "L6004"
			(at 0 0 90)
			(layer "B.SilkS")
			(hide yes)
			(effects
				(font
					(size 1.27 1.27)
				)
				(justify mirror)
			)
		)
		(property "Value" ""
			(at 0 0 90)
			(layer "B.Fab")
			(effects
				(font
					(size 1.27 1.27)
				)
				(justify mirror)
			)
		)
		(duplicate_pad_numbers_are_jumpers no)
		(fp_line
			(start 1.63576 -0.8128)
			(end -1.63576 -0.8128)
			(stroke
				(width 0.1524)
				(type default)
			)
			(layer "B.SilkS")
		)
		(fp_line
			(start 1.63576 -0.8128)
			(end 1.63576 0.8128)
			(stroke
				(width 0.1524)
				(type default)
			)
			(layer "B.SilkS")
		)
		(fp_line
			(start -1.63576 -0.8128)
			(end -1.63576 0.8128)
			(stroke
				(width 0.1524)
				(type default)
			)
			(layer "B.SilkS")
		)
		(fp_line
			(start -1.63576 0.8128)
			(end 1.63576 0.8128)
			(stroke
				(width 0.1524)
				(type default)
			)
			(layer "B.SilkS")
		)
		(fp_line
			(start 1.56083 -0.738632)
			(end 1.56083 0.7366)
			(stroke
				(width 0.1)
				(type default)
			)
			(layer "B.Fab")
		)
		(fp_line
			(start -1.560576 -0.738632)
			(end 1.56083 -0.738632)
			(stroke
				(width 0.1)
				(type default)
			)
			(layer "B.Fab")
		)
		(fp_line
			(start 1.56083 0.7366)
			(end 1.524 0.7366)
			(stroke
				(width 0.1)
				(type default)
			)
			(layer "B.Fab")
		)
		(fp_line
			(start 1.524 0.7366)
			(end -1.524 0.7366)
			(stroke
				(width 0.1)
				(type default)
			)
			(layer "B.Fab")
		)
		(fp_line
			(start -1.524 0.7366)
			(end -1.560576 0.7366)
			(stroke
				(width 0.1)
				(type default)
			)
			(layer "B.Fab")
		)
		(fp_line
			(start -1.560576 0.7366)
			(end -1.560576 -0.738632)
			(stroke
				(width 0.1)
				(type default)
			)
			(layer "B.Fab")
		)
		(pad "1" smd rect
			(at 0.94996 0 90)
			(size 1.1176 1.3716)
			(layers "B.Cu" "B.Mask" "B.Paste")
			(net "P1V2_AUX")
		)
		(pad "2" smd rect
			(at -0.94996 0 90)
			(size 1.1176 1.3716)
			(layers "B.Cu" "B.Mask" "B.Paste")
			(net "P1V2_CPU0_USB2_DVDD12")
		)
	)
	(footprint ""
		(layer "B.Cu")
		(at 64.318642 -388.011162 -90)
		(property "Reference" "C192"
			(at 0 0 90)
			(layer "B.SilkS")
			(hide yes)
			(effects
				(font
					(size 1.27 1.27)
				)
				(justify mirror)
			)
		)
		(property "Value" ""
			(at 0 0 90)
			(layer "B.Fab")
			(effects
				(font
					(size 1.27 1.27)
				)
				(justify mirror)
			)
		)
		(duplicate_pad_numbers_are_jumpers no)
		(fp_line
			(start -0.299974 0.150114)
			(end 0.299974 0.150114)
			(stroke
				(width 0.1)
				(type default)
			)
			(layer "B.Fab")
		)
		(fp_line
			(start 0.299974 0.150114)
			(end 0.299974 -0.150114)
			(stroke
				(width 0.1)
				(type default)
			)
			(layer "B.Fab")
		)
		(fp_line
			(start -0.299974 -0.150114)
			(end -0.299974 0.150114)
			(stroke
				(width 0.1)
				(type default)
			)
			(layer "B.Fab")
		)
		(fp_line
			(start 0.299974 -0.150114)
			(end -0.299974 -0.150114)
			(stroke
				(width 0.1)
				(type default)
			)
			(layer "B.Fab")
		)
		(pad "1" smd rect
			(at 0.2667 0 90)
			(size 0.3048 0.381)
			(layers "B.Cu" "B.Mask" "B.Paste")
			(net "P0V9_CPU1_RT0_2A")
		)
		(pad "2" smd rect
			(at -0.2667 0 90)
			(size 0.3048 0.381)
			(layers "B.Cu" "B.Mask" "B.Paste")
			(net "GND")
		)
	)
	(footprint ""
		(layer "B.Cu")
		(at 108.712 -417.83 90)
		(property "Reference" "C1804"
			(at 0 0 90)
			(layer "B.SilkS")
			(hide yes)
			(effects
				(font
					(size 1.27 1.27)
				)
				(justify mirror)
			)
		)
		(property "Value" ""
			(at 0 0 90)
			(layer "B.Fab")
			(effects
				(font
					(size 1.27 1.27)
				)
				(justify mirror)
			)
		)
		(duplicate_pad_numbers_are_jumpers no)
		(fp_line
			(start 0.7874 -0.4064)
			(end -0.7874 -0.4064)
			(stroke
				(width 0.1524)
				(type default)
			)
			(layer "B.SilkS")
		)
		(fp_line
			(start -0.7874 -0.4064)
			(end -0.7874 0.4064)
			(stroke
				(width 0.1524)
				(type default)
			)
			(layer "B.SilkS")
		)
		(fp_line
			(start 0.7874 0.4064)
			(end 0.7874 -0.4064)
			(stroke
				(width 0.1524)
				(type default)
			)
			(layer "B.SilkS")
		)
		(fp_line
			(start -0.7874 0.4064)
			(end 0.7874 0.4064)
			(stroke
				(width 0.1524)
				(type default)
			)
			(layer "B.SilkS")
		)
		(fp_line
			(start 0.67945 -0.305054)
			(end 0.12065 -0.305054)
			(stroke
				(width 0.1)
				(type default)
			)
			(layer "B.Fab")
		)
		(fp_line
			(start 0.12065 -0.305054)
			(end 0.12065 -0.2794)
			(stroke
				(width 0.1)
				(type default)
			)
			(layer "B.Fab")
		)
		(fp_line
			(start -0.12065 -0.3048)
			(end -0.67945 -0.3048)
			(stroke
				(width 0.1)
				(type default)
			)
			(layer "B.Fab")
		)
		(fp_line
			(start -0.67945 -0.3048)
			(end -0.67945 0.3048)
			(stroke
				(width 0.1)
				(type default)
			)
			(layer "B.Fab")
		)
		(fp_line
			(start 0.12065 -0.2794)
			(end -0.12065 -0.2794)
			(stroke
				(width 0.1)
				(type default)
			)
			(layer "B.Fab")
		)
		(fp_line
			(start -0.12065 -0.2794)
			(end -0.12065 -0.3048)
			(stroke
				(width 0.1)
				(type default)
			)
			(layer "B.Fab")
		)
		(fp_line
			(start 0.12065 0.2794)
			(end 0.12065 0.3048)
			(stroke
				(width 0.1)
				(type default)
			)
			(layer "B.Fab")
		)
		(fp_line
			(start -0.120396 0.2794)
			(end 0.12065 0.2794)
			(stroke
				(width 0.1)
				(type default)
			)
			(layer "B.Fab")
		)
		(fp_line
			(start 0.67945 0.3048)
			(end 0.67945 -0.305054)
			(stroke
				(width 0.1)
				(type default)
			)
			(layer "B.Fab")
		)
		(fp_line
			(start 0.12065 0.3048)
			(end 0.67945 0.3048)
			(stroke
				(width 0.1)
				(type default)
			)
			(layer "B.Fab")
		)
		(fp_line
			(start -0.120396 0.3048)
			(end -0.120396 0.2794)
			(stroke
				(width 0.1)
				(type default)
			)
			(layer "B.Fab")
		)
		(fp_line
			(start -0.67945 0.3048)
			(end -0.120396 0.3048)
			(stroke
				(width 0.1)
				(type default)
			)
			(layer "B.Fab")
		)
		(pad "1" smd circle
			(at 0.40005 0 270)
			(size 0 0)
			(layers "B.Cu" "B.Mask" "B.Paste")
			(net "FM_SMB_2_ALERT_GPU_ISO_N")
		)
		(pad "2" smd circle
			(at -0.40005 0 270)
			(size 0 0)
			(layers "B.Cu" "B.Mask" "B.Paste")
			(net "GND")
		)
	)
	(footprint ""
		(layer "B.Cu")
		(at 439.029602 -422.52011)
		(property "Reference" "PR6819"
			(at 0 0 0)
			(layer "B.SilkS")
			(hide yes)
			(effects
				(font
					(size 1.27 1.27)
				)
				(justify mirror)
			)
		)
		(property "Value" ""
			(at 0 0 0)
			(layer "B.Fab")
			(effects
				(font
					(size 1.27 1.27)
				)
				(justify mirror)
			)
		)
		(duplicate_pad_numbers_are_jumpers no)
		(fp_line
			(start -0.7874 -0.4064)
			(end -0.7874 0.4064)
			(stroke
				(width 0.1524)
				(type default)
			)
			(layer "B.SilkS")
		)
		(fp_line
			(start -0.7874 0.4064)
			(end 0.7874 0.4064)
			(stroke
				(width 0.1524)
				(type default)
			)
			(layer "B.SilkS")
		)
		(fp_line
			(start 0.7874 -0.4064)
			(end -0.7874 -0.4064)
			(stroke
				(width 0.1524)
				(type default)
			)
			(layer "B.SilkS")
		)
		(fp_line
			(start 0.7874 0.4064)
			(end 0.7874 -0.4064)
			(stroke
				(width 0.1524)
				(type default)
			)
			(layer "B.SilkS")
		)
		(fp_line
			(start -0.67945 -0.3048)
			(end -0.67945 0.3048)
			(stroke
				(width 0.1)
				(type default)
			)
			(layer "B.Fab")
		)
		(fp_line
			(start -0.67945 0.3048)
			(end -0.120396 0.3048)
			(stroke
				(width 0.1)
				(type default)
			)
			(layer "B.Fab")
		)
		(fp_line
			(start -0.12065 -0.3048)
			(end -0.67945 -0.3048)
			(stroke
				(width 0.1)
				(type default)
			)
			(layer "B.Fab")
		)
		(fp_line
			(start -0.12065 -0.2794)
			(end -0.12065 -0.3048)
			(stroke
				(width 0.1)
				(type default)
			)
			(layer "B.Fab")
		)
		(fp_line
			(start -0.120396 0.2794)
			(end 0.12065 0.2794)
			(stroke
				(width 0.1)
				(type default)
			)
			(layer "B.Fab")
		)
		(fp_line
			(start -0.120396 0.3048)
			(end -0.120396 0.2794)
			(stroke
				(width 0.1)
				(type default)
			)
			(layer "B.Fab")
		)
		(fp_line
			(start 0.12065 -0.305054)
			(end 0.12065 -0.2794)
			(stroke
				(width 0.1)
				(type default)
			)
			(layer "B.Fab")
		)
		(fp_line
			(start 0.12065 -0.2794)
			(end -0.12065 -0.2794)
			(stroke
				(width 0.1)
				(type default)
			)
			(layer "B.Fab")
		)
		(fp_line
			(start 0.12065 0.2794)
			(end 0.12065 0.3048)
			(stroke
				(width 0.1)
				(type default)
			)
			(layer "B.Fab")
		)
		(fp_line
			(start 0.12065 0.3048)
			(end 0.67945 0.3048)
			(stroke
				(width 0.1)
				(type default)
			)
			(layer "B.Fab")
		)
		(fp_line
			(start 0.67945 -0.305054)
			(end 0.12065 -0.305054)
			(stroke
				(width 0.1)
				(type default)
			)
			(layer "B.Fab")
		)
		(fp_line
			(start 0.67945 0.3048)
			(end 0.67945 -0.305054)
			(stroke
				(width 0.1)
				(type default)
			)
			(layer "B.Fab")
		)
		(pad "1" smd circle
			(at 0.40005 0 180)
			(size 0 0)
			(layers "B.Cu" "B.Mask" "B.Paste")
			(net "P0V9_RETIMER_CPU0_SVID_SDA")
		)
		(pad "2" smd circle
			(at -0.40005 0 180)
			(size 0 0)
			(layers "B.Cu" "B.Mask" "B.Paste")
			(net "GND")
		)
	)
	(footprint ""
		(layer "B.Cu")
		(at 172.877734 -8.062468 -90)
		(property "Reference" "R3242"
			(at 0 0 90)
			(layer "B.SilkS")
			(hide yes)
			(effects
				(font
					(size 1.27 1.27)
				)
				(justify mirror)
			)
		)
		(property "Value" ""
			(at 0 0 90)
			(layer "B.Fab")
			(effects
				(font
					(size 1.27 1.27)
				)
				(justify mirror)
			)
		)
		(duplicate_pad_numbers_are_jumpers no)
		(fp_line
			(start -0.7874 0.4064)
			(end 0.7874 0.4064)
			(stroke
				(width 0.1524)
				(type default)
			)
			(layer "B.SilkS")
		)
		(fp_line
			(start 0.7874 0.4064)
			(end 0.7874 -0.4064)
			(stroke
				(width 0.1524)
				(type default)
			)
			(layer "B.SilkS")
		)
		(fp_line
			(start -0.7874 -0.4064)
			(end -0.7874 0.4064)
			(stroke
				(width 0.1524)
				(type default)
			)
			(layer "B.SilkS")
		)
		(fp_line
			(start 0.7874 -0.4064)
			(end -0.7874 -0.4064)
			(stroke
				(width 0.1524)
				(type default)
			)
			(layer "B.SilkS")
		)
		(fp_line
			(start -0.67945 0.3048)
			(end -0.120396 0.3048)
			(stroke
				(width 0.1)
				(type default)
			)
			(layer "B.Fab")
		)
		(fp_line
			(start -0.120396 0.3048)
			(end -0.120396 0.2794)
			(stroke
				(width 0.1)
				(type default)
			)
			(layer "B.Fab")
		)
		(fp_line
			(start 0.12065 0.3048)
			(end 0.67945 0.3048)
			(stroke
				(width 0.1)
				(type default)
			)
			(layer "B.Fab")
		)
		(fp_line
			(start 0.67945 0.3048)
			(end 0.67945 -0.305054)
			(stroke
				(width 0.1)
				(type default)
			)
			(layer "B.Fab")
		)
		(fp_line
			(start -0.120396 0.2794)
			(end 0.12065 0.2794)
			(stroke
				(width 0.1)
				(type default)
			)
			(layer "B.Fab")
		)
		(fp_line
			(start 0.12065 0.2794)
			(end 0.12065 0.3048)
			(stroke
				(width 0.1)
				(type default)
			)
			(layer "B.Fab")
		)
		(fp_line
			(start -0.12065 -0.2794)
			(end -0.12065 -0.3048)
			(stroke
				(width 0.1)
				(type default)
			)
			(layer "B.Fab")
		)
		(fp_line
			(start 0.12065 -0.2794)
			(end -0.12065 -0.2794)
			(stroke
				(width 0.1)
				(type default)
			)
			(layer "B.Fab")
		)
		(fp_line
			(start -0.67945 -0.3048)
			(end -0.67945 0.3048)
			(stroke
				(width 0.1)
				(type default)
			)
			(layer "B.Fab")
		)
		(fp_line
			(start -0.12065 -0.3048)
			(end -0.67945 -0.3048)
			(stroke
				(width 0.1)
				(type default)
			)
			(layer "B.Fab")
		)
		(fp_line
			(start 0.12065 -0.305054)
			(end 0.12065 -0.2794)
			(stroke
				(width 0.1)
				(type default)
			)
			(layer "B.Fab")
		)
		(fp_line
			(start 0.67945 -0.305054)
			(end 0.12065 -0.305054)
			(stroke
				(width 0.1)
				(type default)
			)
			(layer "B.Fab")
		)
		(pad "1" smd circle
			(at 0.40005 0 90)
			(size 0 0)
			(layers "B.Cu" "B.Mask" "B.Paste")
			(net "SMB_OCP_V3_2_3V3AUX_SCL")
		)
		(pad "2" smd circle
			(at -0.40005 0 90)
			(size 0 0)
			(layers "B.Cu" "B.Mask" "B.Paste")
			(net "P3V3_AUX")
		)
	)
	(footprint ""
		(layer "B.Cu")
		(at 359.173018 -395.466062 -90)
		(property "Reference" "C587"
			(at 0 0 90)
			(layer "B.SilkS")
			(hide yes)
			(effects
				(font
					(size 1.27 1.27)
				)
				(justify mirror)
			)
		)
		(property "Value" ""
			(at 0 0 90)
			(layer "B.Fab")
			(effects
				(font
					(size 1.27 1.27)
				)
				(justify mirror)
			)
		)
		(duplicate_pad_numbers_are_jumpers no)
		(fp_line
			(start -1.524 0.762)
			(end 1.524 0.762)
			(stroke
				(width 0.1524)
				(type default)
			)
			(layer "B.SilkS")
		)
		(fp_line
			(start 1.524 0.762)
			(end 1.524 -0.762)
			(stroke
				(width 0.1524)
				(type default)
			)
			(layer "B.SilkS")
		)
		(fp_line
			(start -1.524 -0.762)
			(end -1.524 0.762)
			(stroke
				(width 0.1524)
				(type default)
			)
			(layer "B.SilkS")
		)
		(fp_line
			(start 1.524 -0.762)
			(end -1.524 -0.762)
			(stroke
				(width 0.1524)
				(type default)
			)
			(layer "B.SilkS")
		)
		(fp_line
			(start -1.1049 0.724916)
			(end -1.1049 -0.724916)
			(stroke
				(width 0.1)
				(type default)
			)
			(layer "B.Fab")
		)
		(fp_line
			(start 1.1049 0.724916)
			(end -1.1049 0.724916)
			(stroke
				(width 0.1)
				(type default)
			)
			(layer "B.Fab")
		)
		(fp_line
			(start -1.1049 -0.724916)
			(end 1.1049 -0.724916)
			(stroke
				(width 0.1)
				(type default)
			)
			(layer "B.Fab")
		)
		(fp_line
			(start 1.1049 -0.724916)
			(end 1.1049 0.724916)
			(stroke
				(width 0.1)
				(type default)
			)
			(layer "B.Fab")
		)
		(pad "1" smd rect
			(at 0.889 0 270)
			(size 1.016 1.27)
			(layers "B.Cu" "B.Mask" "B.Paste")
			(net "P1V8_CPU0_RT_1D")
		)
		(pad "2" smd rect
			(at -0.889 0 270)
			(size 1.016 1.27)
			(layers "B.Cu" "B.Mask" "B.Paste")
			(net "GND")
		)
	)
	(footprint ""
		(layer "B.Cu")
		(at 141.623542 -385.58216 180)
		(property "Reference" "R878"
			(at 0 0 0)
			(layer "B.SilkS")
			(hide yes)
			(effects
				(font
					(size 1.27 1.27)
				)
				(justify mirror)
			)
		)
		(property "Value" ""
			(at 0 0 0)
			(layer "B.Fab")
			(effects
				(font
					(size 1.27 1.27)
				)
				(justify mirror)
			)
		)
		(duplicate_pad_numbers_are_jumpers no)
		(fp_line
			(start 0.32512 0.175006)
			(end 0.32512 -0.175006)
			(stroke
				(width 0.1)
				(type default)
			)
			(layer "B.Fab")
		)
		(fp_line
			(start 0.32512 -0.175006)
			(end -0.32512 -0.175006)
			(stroke
				(width 0.1)
				(type default)
			)
			(layer "B.Fab")
		)
		(fp_line
			(start -0.32512 0.175006)
			(end 0.32512 0.175006)
			(stroke
				(width 0.1)
				(type default)
			)
			(layer "B.Fab")
		)
		(fp_line
			(start -0.32512 -0.175006)
			(end -0.32512 0.175006)
			(stroke
				(width 0.1)
				(type default)
			)
			(layer "B.Fab")
		)
		(pad "1" smd rect
			(at 0.2667 0)
			(size 0.3048 0.381)
			(layers "B.Cu" "B.Mask" "B.Paste")
			(net "P1V8_CPU1_RT_1D")
		)
		(pad "2" smd rect
			(at -0.2667 0 180)
			(size 0.3048 0.381)
			(layers "B.Cu" "B.Mask" "B.Paste")
			(net "TEST0_RT_CPU1_P2")
		)
	)
)
